# T6G (Grand Teton) — schematic netlist excerpt (pin names and nets, part order shuffled) for the footprints in the layout excerpt that follows; sources: Cadence DE-HDL packaged netlist, KiCad conversion of 04192023_DAF0TMB3IC0_F0TG_MB_C_brd_V02_OCP.brd

PC155  Q_CAP  0.22UF 16V 10% X7R  pkg 0402  page 205 : A = SW_PVDDIO_P0_BOOT1_R ; B = SW_PVDDIO_P0_BOOTR1
PC164  Q_CAPP  270UF 16V 20% OSCON  pkg THLF  page 205 : A = SW_P12V_AUX_PVDDIO_P0_FLT ; B = GND
R3682  Q_RES  0 5% CHIP  pkg 0402LF  page 257 : A = P3V3_AUX_ADC ; B = P3V3_AUX_ADC_TIC

(kicad_pcb
	(version 20260206)
	(generator "pcbnew")
	(generator_version "10.0")
	(general
		(thickness 1.6)
		(legacy_teardrops no)
	)
	(paper "A4")
	(title_block
		(title "04192023_DAF0TMB3IC0_F0TG_MB_C_brd_V02_OCP.brd")
		(comment 1 "Grand Teton / footprints 1587-1589 of 8354")
	)
	(layers
		(0 "F.Cu" signal "TOP")
		(4 "In1.Cu" signal "GND")
		(6 "In2.Cu" signal "IN1")
		(8 "In3.Cu" signal "GND1")
		(10 "In4.Cu" signal "IN2")
		(12 "In5.Cu" signal "GND2")
		(14 "In6.Cu" signal "IN3")
		(16 "In7.Cu" signal "GND3")
		(18 "In8.Cu" signal "VCC")
		(20 "In9.Cu" signal "VCC1")
		(22 "In10.Cu" signal "GND4")
		(24 "In11.Cu" signal "IN4")
		(26 "In12.Cu" signal "GND5")
		(28 "In13.Cu" signal "IN5")
		(30 "In14.Cu" signal "GND6")
		(32 "In15.Cu" signal "IN6")
		(34 "In16.Cu" signal "GND7")
		(2 "B.Cu" signal "BOTTOM")
		(9 "F.Adhes" user "F.Adhesive")
		(11 "B.Adhes" user "B.Adhesive")
		(13 "F.Paste" user "Package Geometry/Pastemask Top")
		(15 "B.Paste" user "Package Geometry/Pastemask Bottom")
		(5 "F.SilkS" user "Ref Des/Silkscreen Top")
		(7 "B.SilkS" user "Ref Des/Silkscreen Bottom")
		(1 "F.Mask" user "Board Geometry/Soldermask Top")
		(3 "B.Mask" user "Board Geometry/Soldermask Bottom")
		(17 "Dwgs.User" user "User.Drawings")
		(19 "Cmts.User" user "User.Comments")
		(21 "Eco1.User" user "User.Eco1")
		(23 "Eco2.User" user "User.Eco2")
		(25 "Edge.Cuts" user "Board Geometry/Outline")
		(27 "Margin" user)
		(31 "F.CrtYd" user "Package Geometry/Place Bound Top")
		(29 "B.CrtYd" user "Package Geometry/Place Bound Bottom")
		(35 "F.Fab" user "Ref Des/Assembly Top")
		(33 "B.Fab" user "Ref Des/Assembly Bottom")
	)
	(footprint ""
		(layer "F.Cu")
		(at 322.837048 -41.160954 180)
		(property "Reference" "R3682"
			(at 0 0 180)
			(layer "F.SilkS")
			(hide yes)
			(effects
				(font
					(size 1.27 1.27)
				)
			)
		)
		(property "Value" ""
			(at 0 0 180)
			(layer "F.Fab")
			(effects
				(font
					(size 1.27 1.27)
				)
			)
		)
		(duplicate_pad_numbers_are_jumpers no)
		(fp_line
			(start 0.7874 0.4064)
			(end -0.7874 0.4064)
			(stroke
				(width 0.1524)
				(type default)
			)
			(layer "F.SilkS")
		)
		(fp_line
			(start 0.7874 -0.4064)
			(end 0.7874 0.4064)
			(stroke
				(width 0.1524)
				(type default)
			)
			(layer "F.SilkS")
		)
		(fp_line
			(start -0.7874 0.4064)
			(end -0.7874 -0.4064)
			(stroke
				(width 0.1524)
				(type default)
			)
			(layer "F.SilkS")
		)
		(fp_line
			(start -0.7874 -0.4064)
			(end 0.7874 -0.4064)
			(stroke
				(width 0.1524)
				(type default)
			)
			(layer "F.SilkS")
		)
		(fp_line
			(start 0.67945 0.3048)
			(end 0.120396 0.3048)
			(stroke
				(width 0.1)
				(type default)
			)
			(layer "F.Fab")
		)
		(fp_line
			(start 0.67945 -0.3048)
			(end 0.67945 0.3048)
			(stroke
				(width 0.1)
				(type default)
			)
			(layer "F.Fab")
		)
		(fp_line
			(start 0.12065 -0.2794)
			(end 0.12065 -0.3048)
			(stroke
				(width 0.1)
				(type default)
			)
			(layer "F.Fab")
		)
		(fp_line
			(start 0.12065 -0.3048)
			(end 0.67945 -0.3048)
			(stroke
				(width 0.1)
				(type default)
			)
			(layer "F.Fab")
		)
		(fp_line
			(start 0.120396 0.3048)
			(end 0.120396 0.2794)
			(stroke
				(width 0.1)
				(type default)
			)
			(layer "F.Fab")
		)
		(fp_line
			(start 0.120396 0.2794)
			(end -0.12065 0.2794)
			(stroke
				(width 0.1)
				(type default)
			)
			(layer "F.Fab")
		)
		(fp_line
			(start -0.12065 0.3048)
			(end -0.67945 0.3048)
			(stroke
				(width 0.1)
				(type default)
			)
			(layer "F.Fab")
		)
		(fp_line
			(start -0.12065 0.2794)
			(end -0.12065 0.3048)
			(stroke
				(width 0.1)
				(type default)
			)
			(layer "F.Fab")
		)
		(fp_line
			(start -0.12065 -0.2794)
			(end 0.12065 -0.2794)
			(stroke
				(width 0.1)
				(type default)
			)
			(layer "F.Fab")
		)
		(fp_line
			(start -0.12065 -0.305054)
			(end -0.12065 -0.2794)
			(stroke
				(width 0.1)
				(type default)
			)
			(layer "F.Fab")
		)
		(fp_line
			(start -0.67945 0.3048)
			(end -0.67945 -0.305054)
			(stroke
				(width 0.1)
				(type default)
			)
			(layer "F.Fab")
		)
		(fp_line
			(start -0.67945 -0.305054)
			(end -0.12065 -0.305054)
			(stroke
				(width 0.1)
				(type default)
			)
			(layer "F.Fab")
		)
		(pad "1" smd rect
			(at -0.40005 0)
			(size 0.4572 0.508)
			(layers "F.Cu" "F.Mask" "F.Paste")
			(net "P3V3_AUX_ADC")
		)
		(pad "2" smd rect
			(at 0.40005 0)
			(size 0.4572 0.508)
			(layers "F.Cu" "F.Mask" "F.Paste")
			(net "P3V3_AUX_ADC_TIC")
		)
	)
	(footprint ""
		(layer "F.Cu")
		(at 302.15078 -351.368106 -90)
		(property "Reference" "PC155"
			(at 0 0 270)
			(layer "F.SilkS")
			(hide yes)
			(effects
				(font
					(size 1.27 1.27)
				)
			)
		)
		(property "Value" ""
			(at 0 0 270)
			(layer "F.Fab")
			(effects
				(font
					(size 1.27 1.27)
				)
			)
		)
		(duplicate_pad_numbers_are_jumpers no)
		(fp_line
			(start -0.7874 0.4064)
			(end -0.7874 -0.4064)
			(stroke
				(width 0.1524)
				(type default)
			)
			(layer "F.SilkS")
		)
		(fp_line
			(start 0.7874 0.4064)
			(end -0.7874 0.4064)
			(stroke
				(width 0.1524)
				(type default)
			)
			(layer "F.SilkS")
		)
		(fp_line
			(start -0.7874 -0.4064)
			(end 0.7874 -0.4064)
			(stroke
				(width 0.1524)
				(type default)
			)
			(layer "F.SilkS")
		)
		(fp_line
			(start 0.7874 -0.4064)
			(end 0.7874 0.4064)
			(stroke
				(width 0.1524)
				(type default)
			)
			(layer "F.SilkS")
		)
		(fp_line
			(start -0.67945 0.3048)
			(end -0.67945 -0.305054)
			(stroke
				(width 0.1)
				(type default)
			)
			(layer "F.Fab")
		)
		(fp_line
			(start -0.12065 0.3048)
			(end -0.67945 0.3048)
			(stroke
				(width 0.1)
				(type default)
			)
			(layer "F.Fab")
		)
		(fp_line
			(start 0.120396 0.3048)
			(end 0.120396 0.2794)
			(stroke
				(width 0.1)
				(type default)
			)
			(layer "F.Fab")
		)
		(fp_line
			(start 0.67945 0.3048)
			(end 0.120396 0.3048)
			(stroke
				(width 0.1)
				(type default)
			)
			(layer "F.Fab")
		)
		(fp_line
			(start -0.12065 0.2794)
			(end -0.12065 0.3048)
			(stroke
				(width 0.1)
				(type default)
			)
			(layer "F.Fab")
		)
		(fp_line
			(start 0.120396 0.2794)
			(end -0.12065 0.2794)
			(stroke
				(width 0.1)
				(type default)
			)
			(layer "F.Fab")
		)
		(fp_line
			(start -0.12065 -0.2794)
			(end 0.12065 -0.2794)
			(stroke
				(width 0.1)
				(type default)
			)
			(layer "F.Fab")
		)
		(fp_line
			(start 0.12065 -0.2794)
			(end 0.12065 -0.3048)
			(stroke
				(width 0.1)
				(type default)
			)
			(layer "F.Fab")
		)
		(fp_line
			(start 0.12065 -0.3048)
			(end 0.67945 -0.3048)
			(stroke
				(width 0.1)
				(type default)
			)
			(layer "F.Fab")
		)
		(fp_line
			(start 0.67945 -0.3048)
			(end 0.67945 0.3048)
			(stroke
				(width 0.1)
				(type default)
			)
			(layer "F.Fab")
		)
		(fp_line
			(start -0.67945 -0.305054)
			(end -0.12065 -0.305054)
			(stroke
				(width 0.1)
				(type default)
			)
			(layer "F.Fab")
		)
		(fp_line
			(start -0.12065 -0.305054)
			(end -0.12065 -0.2794)
			(stroke
				(width 0.1)
				(type default)
			)
			(layer "F.Fab")
		)
		(pad "1" smd circle
			(at -0.40005 0 270)
			(size 0 0)
			(layers "F.Cu" "F.Mask" "F.Paste")
			(net "SW_PVDDIO_P0_BOOT1_R")
		)
		(pad "2" smd circle
			(at 0.40005 0 270)
			(size 0 0)
			(layers "F.Cu" "F.Mask" "F.Paste")
			(net "SW_PVDDIO_P0_BOOTR1")
		)
	)
	(footprint ""
		(layer "F.Cu")
		(at 296.29989 -358.769666 180)
		(property "Reference" "PC164"
			(at 1.78689 5.439664 0)
			(unlocked yes)
			(layer "F.SilkS")
			(effects
				(font
					(size 0.7874 0.5842)
					(thickness 0.1524)
				)
				(justify left)
			)
		)
		(property "Value" ""
			(at 0 0 180)
			(layer "F.Fab")
			(effects
				(font
					(size 1.27 1.27)
				)
			)
		)
		(duplicate_pad_numbers_are_jumpers no)
		(fp_line
			(start -3.400044 1.249934)
			(end 3.400044 1.249934)
			(stroke
				(width 0.1524)
				(type default)
			)
			(layer "F.SilkS")
		)
		(fp_circle
			(center 0 1.249934)
			(end -3.400044 1.249934)
			(stroke
				(width 0.1524)
				(type default)
			)
			(fill no)
			(layer "F.SilkS")
		)
		(fp_poly
			(pts
				(arc
					(start 3.400044 1.249934)
					(mid 0 4.649978)
					(end -3.400044 1.249934)
				)
			)
			(stroke
				(width 0)
				(type default)
			)
			(fill yes)
			(layer "F.SilkS")
		)
		(fp_circle
			(center 0 1.249934)
			(end -3.400044 1.249934)
			(stroke
				(width 0.1)
				(type default)
			)
			(fill no)
			(layer "F.Fab")
		)
		(pad "1" thru_hole rect
			(at 0 0 180)
			(size 1.524 1.524)
			(drill 1.016)
			(layers "*.Cu" "*.Mask")
			(remove_unused_layers no)
			(net "SW_P12V_AUX_PVDDIO_P0_FLT")
			(clearance 0)
			(padstack
				(mode front_inner_back)
				(layer "Inner"
					(shape circle)
					(size 1.524 1.524)
					(clearance 0)
				)
				(layer "B.Cu"
					(shape rect)
					(size 1.524 1.524)
					(clearance 0)
				)
			)
		)
		(pad "2" thru_hole circle
			(at 0 2.500122 180)
			(size 1.524 1.524)
			(drill 1.016)
			(layers "*.Cu" "*.Mask")
			(remove_unused_layers no)
			(net "GND")
			(clearance 0)
		)
	)
)
